# S9S_MB_2U (Grand Teton) — schematic netlist excerpt (pin names and nets, part order shuffled) for the footprints in the layout excerpt that follows; sources: Cadence DE-HDL packaged netlist, KiCad conversion of 03242023_DA0F0TMBIJ0_F0T_Motherboard_J_brd_V01_OCP.brd

U269  ADC128D818CIMTXNOPB  ADC128D818CIMTX/NOPB IC  pkg TSSOP16XC  page 250
  VREF  = ADC128_VREF
  SDA  = SMB_SEN_TIC_3V3AUX_SDA
  SCL  = SMB_SEN_TIC_3V3AUX_SCL
  GND  = GND
  \v+\  = P3V3_ADC128_VCC
  \int#\  = TP_ADC128_INT
  A0  = ADC128_A0
  A1  = ADC128_A1
  IN7  = P12V_E1S_0_ISENSE_TIC
  IN6  = P3V3_PDB_AUX_ADC_TIC
  IN5  = P3V3_AUX_ADC_TIC
  IN4  = P3V3_ADC_TIC
  IN3  = P5V_ADC_TIC
  IN2  = P12V_OCP_V3_2_ISENSE_TIC
  IN1  = P12V_OCP_SFF_ISENSE_TIC
  IN0  = P12V_AUX_ADC_TIC

R2916  Q_RES  4.7K 5% EMPTY  pkg 0402LF  page 151 : A = RST_SWB_BIC_R_N ; B = GND

(kicad_pcb
	(version 20260206)
	(generator "pcbnew")
	(generator_version "10.0")
	(general
		(thickness 1.6)
		(legacy_teardrops no)
	)
	(paper "A4")
	(title_block
		(title "03242023_DA0F0TMBIJ0_F0T_Motherboard_J_brd_V01_OCP.brd")
		(comment 1 "Grand Teton / footprints 1901-1902 of 6105")
	)
	(layers
		(0 "F.Cu" signal "TOP")
		(4 "In1.Cu" signal "GND")
		(6 "In2.Cu" signal "IN1")
		(8 "In3.Cu" signal "GND1")
		(10 "In4.Cu" signal "IN2")
		(12 "In5.Cu" signal "GND2")
		(14 "In6.Cu" signal "IN3")
		(16 "In7.Cu" signal "GND3")
		(18 "In8.Cu" signal "VCC")
		(20 "In9.Cu" signal "VCC1")
		(22 "In10.Cu" signal "GND4")
		(24 "In11.Cu" signal "IN4")
		(26 "In12.Cu" signal "GND5")
		(28 "In13.Cu" signal "IN5")
		(30 "In14.Cu" signal "GND6")
		(32 "In15.Cu" signal "IN6")
		(34 "In16.Cu" signal "GND7")
		(2 "B.Cu" signal "BOTTOM")
		(9 "F.Adhes" user "F.Adhesive")
		(11 "B.Adhes" user "B.Adhesive")
		(13 "F.Paste" user "Package Geometry/Pastemask Top")
		(15 "B.Paste" user "Package Geometry/Pastemask Bottom")
		(5 "F.SilkS" user "Ref Des/Silkscreen Top")
		(7 "B.SilkS" user "Ref Des/Silkscreen Bottom")
		(1 "F.Mask" user "Board Geometry/Soldermask Top")
		(3 "B.Mask" user "Board Geometry/Soldermask Bottom")
		(17 "Dwgs.User" user "User.Drawings")
		(19 "Cmts.User" user "User.Comments")
		(21 "Eco1.User" user "User.Eco1")
		(23 "Eco2.User" user "User.Eco2")
		(25 "Edge.Cuts" user "Board Geometry/Outline")
		(27 "Margin" user)
		(31 "F.CrtYd" user "Package Geometry/Place Bound Top")
		(29 "B.CrtYd" user "Package Geometry/Place Bound Bottom")
		(35 "F.Fab" user "Ref Des/Assembly Top")
		(33 "B.Fab" user "Ref Des/Assembly Bottom")
	)
	(footprint ""
		(layer "F.Cu")
		(at 29.715714 -109.333538)
		(property "Reference" "U269"
			(at -3.27914 -4.806188 0)
			(unlocked yes)
			(layer "F.SilkS")
			(effects
				(font
					(size 0.7874 0.5842)
					(thickness 0.1524)
				)
				(justify left)
			)
		)
		(property "Value" ""
			(at 0 0 0)
			(layer "F.Fab")
			(effects
				(font
					(size 1.27 1.27)
				)
			)
		)
		(duplicate_pad_numbers_are_jumpers no)
		(fp_line
			(start -1.868932 -2.549906)
			(end -1.868932 2.549906)
			(stroke
				(width 0.1524)
				(type default)
			)
			(layer "F.SilkS")
		)
		(fp_line
			(start -1.868932 2.549906)
			(end 1.868932 2.549906)
			(stroke
				(width 0.1524)
				(type default)
			)
			(layer "F.SilkS")
		)
		(fp_line
			(start -1.025906 -2.549906)
			(end -1.868932 -2.549906)
			(stroke
				(width 0.1524)
				(type default)
			)
			(layer "F.SilkS")
		)
		(fp_line
			(start 0 -1.524)
			(end -1.025906 -2.549906)
			(stroke
				(width 0.1524)
				(type default)
			)
			(layer "F.SilkS")
		)
		(fp_line
			(start 1.025906 -2.549906)
			(end 0 -1.524)
			(stroke
				(width 0.1524)
				(type default)
			)
			(layer "F.SilkS")
		)
		(fp_line
			(start 1.868932 -2.549906)
			(end 1.025906 -2.549906)
			(stroke
				(width 0.1524)
				(type default)
			)
			(layer "F.SilkS")
		)
		(fp_line
			(start 1.868932 2.549906)
			(end 1.868932 -2.549906)
			(stroke
				(width 0.1524)
				(type default)
			)
			(layer "F.SilkS")
		)
		(fp_poly
			(pts
				(xy -2.227326 -3.828796) (xy -2.735326 -2.812796) (xy -3.243326 -3.828796)
			)
			(stroke
				(width 0)
				(type default)
			)
			(fill yes)
			(layer "F.SilkS")
		)
		(fp_line
			(start -2.249932 -2.549906)
			(end -2.249932 2.549906)
			(stroke
				(width 0.1)
				(type default)
			)
			(layer "F.Fab")
		)
		(fp_line
			(start -2.249932 2.549906)
			(end 2.249932 2.549906)
			(stroke
				(width 0.1)
				(type default)
			)
			(layer "F.Fab")
		)
		(fp_line
			(start 2.249932 -2.549906)
			(end -2.249932 -2.549906)
			(stroke
				(width 0.1)
				(type default)
			)
			(layer "F.Fab")
		)
		(fp_line
			(start 2.249932 2.549906)
			(end 2.249932 -2.549906)
			(stroke
				(width 0.1)
				(type default)
			)
			(layer "F.Fab")
		)
		(fp_poly
			(pts
				(xy -4.7752 -1.787398) (xy -4.7752 -2.803398) (xy -3.7592 -2.295398)
			)
			(stroke
				(width 0)
				(type default)
			)
			(fill yes)
			(layer "F.Fab")
		)
		(pad "1" smd rect
			(at -2.800096 -2.275078 270)
			(size 0.3556 1.6002)
			(layers "F.Cu" "F.Mask" "F.Paste")
			(net "ADC128_VREF")
		)
		(pad "2" smd rect
			(at -2.800096 -1.625092 270)
			(size 0.3556 1.6002)
			(layers "F.Cu" "F.Mask" "F.Paste")
			(net "SMB_SEN_TIC_3V3AUX_SDA")
		)
		(pad "3" smd rect
			(at -2.800096 -0.975106 270)
			(size 0.3556 1.6002)
			(layers "F.Cu" "F.Mask" "F.Paste")
			(net "SMB_SEN_TIC_3V3AUX_SCL")
		)
		(pad "4" smd rect
			(at -2.800096 -0.32512 270)
			(size 0.3556 1.6002)
			(layers "F.Cu" "F.Mask" "F.Paste")
			(net "GND")
		)
		(pad "5" smd rect
			(at -2.800096 0.32512 270)
			(size 0.3556 1.6002)
			(layers "F.Cu" "F.Mask" "F.Paste")
			(net "P3V3_ADC128_VCC")
		)
		(pad "6" smd rect
			(at -2.800096 0.975106 270)
			(size 0.3556 1.6002)
			(layers "F.Cu" "F.Mask" "F.Paste")
			(net "TP_ADC128_INT")
		)
		(pad "7" smd rect
			(at -2.800096 1.625092 270)
			(size 0.3556 1.6002)
			(layers "F.Cu" "F.Mask" "F.Paste")
			(net "ADC128_A0")
		)
		(pad "8" smd rect
			(at -2.800096 2.275078 270)
			(size 0.3556 1.6002)
			(layers "F.Cu" "F.Mask" "F.Paste")
			(net "ADC128_A1")
		)
		(pad "9" smd rect
			(at 2.800096 2.275078 270)
			(size 0.3556 1.6002)
			(layers "F.Cu" "F.Mask" "F.Paste")
			(net "P12V_E1S_0_ISENSE_TIC")
		)
		(pad "10" smd rect
			(at 2.800096 1.625092 270)
			(size 0.3556 1.6002)
			(layers "F.Cu" "F.Mask" "F.Paste")
			(net "P3V3_PDB_AUX_ADC_TIC")
		)
		(pad "11" smd rect
			(at 2.800096 0.975106 270)
			(size 0.3556 1.6002)
			(layers "F.Cu" "F.Mask" "F.Paste")
			(net "P3V3_AUX_ADC_TIC")
		)
		(pad "12" smd rect
			(at 2.800096 0.32512 270)
			(size 0.3556 1.6002)
			(layers "F.Cu" "F.Mask" "F.Paste")
			(net "P3V3_ADC_TIC")
		)
		(pad "13" smd rect
			(at 2.800096 -0.32512 270)
			(size 0.3556 1.6002)
			(layers "F.Cu" "F.Mask" "F.Paste")
			(net "P5V_ADC_TIC")
		)
		(pad "14" smd rect
			(at 2.800096 -0.975106 270)
			(size 0.3556 1.6002)
			(layers "F.Cu" "F.Mask" "F.Paste")
			(net "P12V_OCP_V3_2_ISENSE_TIC")
		)
		(pad "15" smd rect
			(at 2.800096 -1.625092 270)
			(size 0.3556 1.6002)
			(layers "F.Cu" "F.Mask" "F.Paste")
			(net "P12V_OCP_SFF_ISENSE_TIC")
		)
		(pad "16" smd rect
			(at 2.800096 -2.275078 270)
			(size 0.3556 1.6002)
			(layers "F.Cu" "F.Mask" "F.Paste")
			(net "P12V_AUX_ADC_TIC")
		)
	)
	(footprint ""
		(layer "F.Cu")
		(at 169.44848 -422.874948 180)
		(property "Reference" "R2916"
			(at 0 0 180)
			(layer "F.SilkS")
			(hide yes)
			(effects
				(font
					(size 1.27 1.27)
				)
			)
		)
		(property "Value" ""
			(at 0 0 180)
			(layer "F.Fab")
			(effects
				(font
					(size 1.27 1.27)
				)
			)
		)
		(duplicate_pad_numbers_are_jumpers no)
		(fp_line
			(start 0.7874 0.4064)
			(end -0.7874 0.4064)
			(stroke
				(width 0.1524)
				(type default)
			)
			(layer "F.SilkS")
		)
		(fp_line
			(start 0.7874 -0.4064)
			(end 0.7874 0.4064)
			(stroke
				(width 0.1524)
				(type default)
			)
			(layer "F.SilkS")
		)
		(fp_line
			(start -0.7874 0.4064)
			(end -0.7874 -0.4064)
			(stroke
				(width 0.1524)
				(type default)
			)
			(layer "F.SilkS")
		)
		(fp_line
			(start -0.7874 -0.4064)
			(end 0.7874 -0.4064)
			(stroke
				(width 0.1524)
				(type default)
			)
			(layer "F.SilkS")
		)
		(fp_line
			(start 0.67945 0.3048)
			(end 0.120396 0.3048)
			(stroke
				(width 0.1)
				(type default)
			)
			(layer "F.Fab")
		)
		(fp_line
			(start 0.67945 -0.3048)
			(end 0.67945 0.3048)
			(stroke
				(width 0.1)
				(type default)
			)
			(layer "F.Fab")
		)
		(fp_line
			(start 0.12065 -0.2794)
			(end 0.12065 -0.3048)
			(stroke
				(width 0.1)
				(type default)
			)
			(layer "F.Fab")
		)
		(fp_line
			(start 0.12065 -0.3048)
			(end 0.67945 -0.3048)
			(stroke
				(width 0.1)
				(type default)
			)
			(layer "F.Fab")
		)
		(fp_line
			(start 0.120396 0.3048)
			(end 0.120396 0.2794)
			(stroke
				(width 0.1)
				(type default)
			)
			(layer "F.Fab")
		)
		(fp_line
			(start 0.120396 0.2794)
			(end -0.12065 0.2794)
			(stroke
				(width 0.1)
				(type default)
			)
			(layer "F.Fab")
		)
		(fp_line
			(start -0.12065 0.3048)
			(end -0.67945 0.3048)
			(stroke
				(width 0.1)
				(type default)
			)
			(layer "F.Fab")
		)
		(fp_line
			(start -0.12065 0.2794)
			(end -0.12065 0.3048)
			(stroke
				(width 0.1)
				(type default)
			)
			(layer "F.Fab")
		)
		(fp_line
			(start -0.12065 -0.2794)
			(end 0.12065 -0.2794)
			(stroke
				(width 0.1)
				(type default)
			)
			(layer "F.Fab")
		)
		(fp_line
			(start -0.12065 -0.305054)
			(end -0.12065 -0.2794)
			(stroke
				(width 0.1)
				(type default)
			)
			(layer "F.Fab")
		)
		(fp_line
			(start -0.67945 0.3048)
			(end -0.67945 -0.305054)
			(stroke
				(width 0.1)
				(type default)
			)
			(layer "F.Fab")
		)
		(fp_line
			(start -0.67945 -0.305054)
			(end -0.12065 -0.305054)
			(stroke
				(width 0.1)
				(type default)
			)
			(layer "F.Fab")
		)
		(pad "1" smd circle
			(at -0.40005 0 180)
			(size 0 0)
			(layers "F.Cu" "F.Mask" "F.Paste")
			(net "RST_SWB_BIC_R_N")
		)
		(pad "2" smd circle
			(at 0.40005 0 180)
			(size 0 0)
			(layers "F.Cu" "F.Mask" "F.Paste")
			(net "GND")
		)
	)
)
